(kicad_pcb
	(version 20260206)
	(generator "pcbnew")
	(generator_version "10.0")
	(general
		(thickness 1.6)
		(legacy_teardrops no)
	)
	(paper "A4")
	(title_block
		(title "9052_F0T_PDB_Converter_Brick_F_V03_1208_1600_OCP.brd")
		(comment 1 "Grand Teton / footprints 547-552 of 578")
	)
	(layers
		(0 "F.Cu" signal "TOP")
		(4 "In1.Cu" signal "GND")
		(6 "In2.Cu" signal "IN1")
		(8 "In3.Cu" signal "GND1")
		(10 "In4.Cu" signal "VCC")
		(12 "In5.Cu" signal "VCC1")
		(14 "In6.Cu" signal "GND2")
		(16 "In7.Cu" signal "IN2")
		(18 "In8.Cu" signal "GND3")
		(2 "B.Cu" signal "BOTTOM")
		(9 "F.Adhes" user "F.Adhesive")
		(11 "B.Adhes" user "B.Adhesive")
		(13 "F.Paste" user "Package Geometry/Pastemask Top")
		(15 "B.Paste" user "Package Geometry/Pastemask Bottom")
		(5 "F.SilkS" user "Ref Des/Silkscreen Top")
		(7 "B.SilkS" user "Ref Des/Silkscreen Bottom")
		(1 "F.Mask" user "Board Geometry/Soldermask Top")
		(3 "B.Mask" user "Board Geometry/Soldermask Bottom")
		(17 "Dwgs.User" user "User.Drawings")
		(19 "Cmts.User" user "User.Comments")
		(21 "Eco1.User" user "User.Eco1")
		(23 "Eco2.User" user "User.Eco2")
		(25 "Edge.Cuts" user "Board Geometry/Outline")
		(27 "Margin" user)
		(31 "F.CrtYd" user "Package Geometry/Place Bound Top")
		(29 "B.CrtYd" user "Package Geometry/Place Bound Bottom")
		(35 "F.Fab" user "Ref Des/Assembly Top")
		(33 "B.Fab" user "Ref Des/Assembly Bottom")
	)
	(footprint ""
		(layer "B.Cu")
		(at 232.537 -70.993 -90)
		(property "Reference" "C15"
			(at 0 0 90)
			(layer "B.SilkS")
			(hide yes)
			(effects
				(font
					(size 1.27 1.27)
				)
				(justify mirror)
			)
		)
		(property "Value" ""
			(at 0 0 90)
			(layer "B.Fab")
			(effects
				(font
					(size 1.27 1.27)
				)
				(justify mirror)
			)
		)
		(duplicate_pad_numbers_are_jumpers no)
		(fp_line
			(start -0.7874 0.4064)
			(end 0.7874 0.4064)
			(stroke
				(width 0.1524)
				(type default)
			)
			(layer "B.SilkS")
		)
		(fp_line
			(start 0.7874 0.4064)
			(end 0.7874 -0.4064)
			(stroke
				(width 0.1524)
				(type default)
			)
			(layer "B.SilkS")
		)
		(fp_line
			(start -0.7874 -0.4064)
			(end -0.7874 0.4064)
			(stroke
				(width 0.1524)
				(type default)
			)
			(layer "B.SilkS")
		)
		(fp_line
			(start 0.7874 -0.4064)
			(end -0.7874 -0.4064)
			(stroke
				(width 0.1524)
				(type default)
			)
			(layer "B.SilkS")
		)
		(fp_line
			(start -0.67945 0.3048)
			(end -0.120396 0.3048)
			(stroke
				(width 0.1)
				(type default)
			)
			(layer "B.Fab")
		)
		(fp_line
			(start -0.120396 0.3048)
			(end -0.120396 0.2794)
			(stroke
				(width 0.1)
				(type default)
			)
			(layer "B.Fab")
		)
		(fp_line
			(start 0.12065 0.3048)
			(end 0.67945 0.3048)
			(stroke
				(width 0.1)
				(type default)
			)
			(layer "B.Fab")
		)
		(fp_line
			(start 0.67945 0.3048)
			(end 0.67945 -0.305054)
			(stroke
				(width 0.1)
				(type default)
			)
			(layer "B.Fab")
		)
		(fp_line
			(start -0.120396 0.2794)
			(end 0.12065 0.2794)
			(stroke
				(width 0.1)
				(type default)
			)
			(layer "B.Fab")
		)
		(fp_line
			(start 0.12065 0.2794)
			(end 0.12065 0.3048)
			(stroke
				(width 0.1)
				(type default)
			)
			(layer "B.Fab")
		)
		(fp_line
			(start -0.12065 -0.2794)
			(end -0.12065 -0.3048)
			(stroke
				(width 0.1)
				(type default)
			)
			(layer "B.Fab")
		)
		(fp_line
			(start 0.12065 -0.2794)
			(end -0.12065 -0.2794)
			(stroke
				(width 0.1)
				(type default)
			)
			(layer "B.Fab")
		)
		(fp_line
			(start -0.67945 -0.3048)
			(end -0.67945 0.3048)
			(stroke
				(width 0.1)
				(type default)
			)
			(layer "B.Fab")
		)
		(fp_line
			(start -0.12065 -0.3048)
			(end -0.67945 -0.3048)
			(stroke
				(width 0.1)
				(type default)
			)
			(layer "B.Fab")
		)
		(fp_line
			(start 0.12065 -0.305054)
			(end 0.12065 -0.2794)
			(stroke
				(width 0.1)
				(type default)
			)
			(layer "B.Fab")
		)
		(fp_line
			(start 0.67945 -0.305054)
			(end 0.12065 -0.305054)
			(stroke
				(width 0.1)
				(type default)
			)
			(layer "B.Fab")
		)
		(pad "1" smd circle
			(at 0.40005 0 90)
			(size 0 0)
			(layers "B.Cu" "B.Mask" "B.Paste")
			(net "PWRGD_P3V3_AUX_MB_R")
		)
		(pad "2" smd circle
			(at -0.40005 0 90)
			(size 0 0)
			(layers "B.Cu" "B.Mask" "B.Paste")
			(net "GND")
		)
	)
	(footprint ""
		(layer "B.Cu")
		(at 267.589 -28.321)
		(property "Reference" "R5918"
			(at 0 0 0)
			(layer "B.SilkS")
			(hide yes)
			(effects
				(font
					(size 1.27 1.27)
				)
				(justify mirror)
			)
		)
		(property "Value" ""
			(at 0 0 0)
			(layer "B.Fab")
			(effects
				(font
					(size 1.27 1.27)
				)
				(justify mirror)
			)
		)
		(duplicate_pad_numbers_are_jumpers no)
		(fp_line
			(start -1.651 -0.8382)
			(end -1.651 0.8382)
			(stroke
				(width 0.1524)
				(type default)
			)
			(layer "B.SilkS")
		)
		(fp_line
			(start -1.651 0.8382)
			(end 1.651 0.8382)
			(stroke
				(width 0.1524)
				(type default)
			)
			(layer "B.SilkS")
		)
		(fp_line
			(start 1.651 -0.8382)
			(end -1.651 -0.8382)
			(stroke
				(width 0.1524)
				(type default)
			)
			(layer "B.SilkS")
		)
		(fp_line
			(start 1.651 0.8382)
			(end 1.651 -0.8382)
			(stroke
				(width 0.1524)
				(type default)
			)
			(layer "B.SilkS")
		)
		(fp_line
			(start -1.560576 -0.7366)
			(end -1.524 -0.7366)
			(stroke
				(width 0.1)
				(type default)
			)
			(layer "B.Fab")
		)
		(fp_line
			(start -1.560576 0.7366)
			(end -1.560576 -0.7366)
			(stroke
				(width 0.1)
				(type default)
			)
			(layer "B.Fab")
		)
		(fp_line
			(start -1.524 -0.7366)
			(end 1.524 -0.7366)
			(stroke
				(width 0.1)
				(type default)
			)
			(layer "B.Fab")
		)
		(fp_line
			(start -1.524 0.7366)
			(end -1.560576 0.7366)
			(stroke
				(width 0.1)
				(type default)
			)
			(layer "B.Fab")
		)
		(fp_line
			(start 1.524 -0.7366)
			(end 1.559814 -0.7366)
			(stroke
				(width 0.1)
				(type default)
			)
			(layer "B.Fab")
		)
		(fp_line
			(start 1.524 0.7366)
			(end -1.524 0.7366)
			(stroke
				(width 0.1)
				(type default)
			)
			(layer "B.Fab")
		)
		(fp_line
			(start 1.559814 -0.7366)
			(end 1.559814 0.7366)
			(stroke
				(width 0.1)
				(type default)
			)
			(layer "B.Fab")
		)
		(fp_line
			(start 1.559814 0.7366)
			(end 1.524 0.7366)
			(stroke
				(width 0.1)
				(type default)
			)
			(layer "B.Fab")
		)
		(pad "1" smd rect
			(at 0.94996 0)
			(size 1.1176 1.3716)
			(layers "B.Cu" "B.Mask" "B.Paste")
			(net "P52V_HS1_EN")
		)
		(pad "2" smd rect
			(at -0.94996 0)
			(size 1.1176 1.3716)
			(layers "B.Cu" "B.Mask" "B.Paste")
			(net "P52V_HS1_EN_DELAY")
		)
	)
	(footprint ""
		(layer "B.Cu")
		(at 209.677 -84.836)
		(property "Reference" "R185"
			(at 0 0 0)
			(layer "B.SilkS")
			(hide yes)
			(effects
				(font
					(size 1.27 1.27)
				)
				(justify mirror)
			)
		)
		(property "Value" ""
			(at 0 0 0)
			(layer "B.Fab")
			(effects
				(font
					(size 1.27 1.27)
				)
				(justify mirror)
			)
		)
		(duplicate_pad_numbers_are_jumpers no)
		(fp_line
			(start -0.7874 -0.4064)
			(end -0.7874 0.4064)
			(stroke
				(width 0.1524)
				(type default)
			)
			(layer "B.SilkS")
		)
		(fp_line
			(start -0.7874 0.4064)
			(end 0.7874 0.4064)
			(stroke
				(width 0.1524)
				(type default)
			)
			(layer "B.SilkS")
		)
		(fp_line
			(start 0.7874 -0.4064)
			(end -0.7874 -0.4064)
			(stroke
				(width 0.1524)
				(type default)
			)
			(layer "B.SilkS")
		)
		(fp_line
			(start 0.7874 0.4064)
			(end 0.7874 -0.4064)
			(stroke
				(width 0.1524)
				(type default)
			)
			(layer "B.SilkS")
		)
		(fp_line
			(start -0.67945 -0.3048)
			(end -0.67945 0.3048)
			(stroke
				(width 0.1)
				(type default)
			)
			(layer "B.Fab")
		)
		(fp_line
			(start -0.67945 0.3048)
			(end -0.120396 0.3048)
			(stroke
				(width 0.1)
				(type default)
			)
			(layer "B.Fab")
		)
		(fp_line
			(start -0.12065 -0.3048)
			(end -0.67945 -0.3048)
			(stroke
				(width 0.1)
				(type default)
			)
			(layer "B.Fab")
		)
		(fp_line
			(start -0.12065 -0.2794)
			(end -0.12065 -0.3048)
			(stroke
				(width 0.1)
				(type default)
			)
			(layer "B.Fab")
		)
		(fp_line
			(start -0.120396 0.2794)
			(end 0.12065 0.2794)
			(stroke
				(width 0.1)
				(type default)
			)
			(layer "B.Fab")
		)
		(fp_line
			(start -0.120396 0.3048)
			(end -0.120396 0.2794)
			(stroke
				(width 0.1)
				(type default)
			)
			(layer "B.Fab")
		)
		(fp_line
			(start 0.12065 -0.305054)
			(end 0.12065 -0.2794)
			(stroke
				(width 0.1)
				(type default)
			)
			(layer "B.Fab")
		)
		(fp_line
			(start 0.12065 -0.2794)
			(end -0.12065 -0.2794)
			(stroke
				(width 0.1)
				(type default)
			)
			(layer "B.Fab")
		)
		(fp_line
			(start 0.12065 0.2794)
			(end 0.12065 0.3048)
			(stroke
				(width 0.1)
				(type default)
			)
			(layer "B.Fab")
		)
		(fp_line
			(start 0.12065 0.3048)
			(end 0.67945 0.3048)
			(stroke
				(width 0.1)
				(type default)
			)
			(layer "B.Fab")
		)
		(fp_line
			(start 0.67945 -0.305054)
			(end 0.12065 -0.305054)
			(stroke
				(width 0.1)
				(type default)
			)
			(layer "B.Fab")
		)
		(fp_line
			(start 0.67945 0.3048)
			(end 0.67945 -0.305054)
			(stroke
				(width 0.1)
				(type default)
			)
			(layer "B.Fab")
		)
		(pad "1" smd circle
			(at 0.40005 0 180)
			(size 0 0)
			(layers "B.Cu" "B.Mask" "B.Paste")
			(net "PWRGD_GPU_HSC")
		)
		(pad "2" smd circle
			(at -0.40005 0 180)
			(size 0 0)
			(layers "B.Cu" "B.Mask" "B.Paste")
			(net "PWRGD_GPU_HSC_R")
		)
	)
	(footprint ""
		(layer "B.Cu")
		(at 214.884 -69.723 -90)
		(property "Reference" "R133"
			(at 0 0 90)
			(layer "B.SilkS")
			(hide yes)
			(effects
				(font
					(size 1.27 1.27)
				)
				(justify mirror)
			)
		)
		(property "Value" ""
			(at 0 0 90)
			(layer "B.Fab")
			(effects
				(font
					(size 1.27 1.27)
				)
				(justify mirror)
			)
		)
		(duplicate_pad_numbers_are_jumpers no)
		(fp_line
			(start -0.7874 0.4064)
			(end 0.7874 0.4064)
			(stroke
				(width 0.1524)
				(type default)
			)
			(layer "B.SilkS")
		)
		(fp_line
			(start 0.7874 0.4064)
			(end 0.7874 -0.4064)
			(stroke
				(width 0.1524)
				(type default)
			)
			(layer "B.SilkS")
		)
		(fp_line
			(start -0.7874 -0.4064)
			(end -0.7874 0.4064)
			(stroke
				(width 0.1524)
				(type default)
			)
			(layer "B.SilkS")
		)
		(fp_line
			(start 0.7874 -0.4064)
			(end -0.7874 -0.4064)
			(stroke
				(width 0.1524)
				(type default)
			)
			(layer "B.SilkS")
		)
		(fp_line
			(start -0.67945 0.3048)
			(end -0.120396 0.3048)
			(stroke
				(width 0.1)
				(type default)
			)
			(layer "B.Fab")
		)
		(fp_line
			(start -0.120396 0.3048)
			(end -0.120396 0.2794)
			(stroke
				(width 0.1)
				(type default)
			)
			(layer "B.Fab")
		)
		(fp_line
			(start 0.12065 0.3048)
			(end 0.67945 0.3048)
			(stroke
				(width 0.1)
				(type default)
			)
			(layer "B.Fab")
		)
		(fp_line
			(start 0.67945 0.3048)
			(end 0.67945 -0.305054)
			(stroke
				(width 0.1)
				(type default)
			)
			(layer "B.Fab")
		)
		(fp_line
			(start -0.120396 0.2794)
			(end 0.12065 0.2794)
			(stroke
				(width 0.1)
				(type default)
			)
			(layer "B.Fab")
		)
		(fp_line
			(start 0.12065 0.2794)
			(end 0.12065 0.3048)
			(stroke
				(width 0.1)
				(type default)
			)
			(layer "B.Fab")
		)
		(fp_line
			(start -0.12065 -0.2794)
			(end -0.12065 -0.3048)
			(stroke
				(width 0.1)
				(type default)
			)
			(layer "B.Fab")
		)
		(fp_line
			(start 0.12065 -0.2794)
			(end -0.12065 -0.2794)
			(stroke
				(width 0.1)
				(type default)
			)
			(layer "B.Fab")
		)
		(fp_line
			(start -0.67945 -0.3048)
			(end -0.67945 0.3048)
			(stroke
				(width 0.1)
				(type default)
			)
			(layer "B.Fab")
		)
		(fp_line
			(start -0.12065 -0.3048)
			(end -0.67945 -0.3048)
			(stroke
				(width 0.1)
				(type default)
			)
			(layer "B.Fab")
		)
		(fp_line
			(start 0.12065 -0.305054)
			(end 0.12065 -0.2794)
			(stroke
				(width 0.1)
				(type default)
			)
			(layer "B.Fab")
		)
		(fp_line
			(start 0.67945 -0.305054)
			(end 0.12065 -0.305054)
			(stroke
				(width 0.1)
				(type default)
			)
			(layer "B.Fab")
		)
		(pad "1" smd circle
			(at 0.40005 0 90)
			(size 0 0)
			(layers "B.Cu" "B.Mask" "B.Paste")
			(net "P3V3_AUX")
		)
		(pad "2" smd circle
			(at -0.40005 0 90)
			(size 0 0)
			(layers "B.Cu" "B.Mask" "B.Paste")
			(net "BOARD_ID_2")
		)
	)
	(footprint ""
		(layer "B.Cu")
		(at 149.733 -114.427 -90)
		(property "Reference" "C55"
			(at 0 0 90)
			(layer "B.SilkS")
			(hide yes)
			(effects
				(font
					(size 1.27 1.27)
				)
				(justify mirror)
			)
		)
		(property "Value" ""
			(at 0 0 90)
			(layer "B.Fab")
			(effects
				(font
					(size 1.27 1.27)
				)
				(justify mirror)
			)
		)
		(duplicate_pad_numbers_are_jumpers no)
		(fp_line
			(start -0.7874 0.4064)
			(end 0.7874 0.4064)
			(stroke
				(width 0.1524)
				(type default)
			)
			(layer "B.SilkS")
		)
		(fp_line
			(start 0.7874 0.4064)
			(end 0.7874 -0.4064)
			(stroke
				(width 0.1524)
				(type default)
			)
			(layer "B.SilkS")
		)
		(fp_line
			(start -0.7874 -0.4064)
			(end -0.7874 0.4064)
			(stroke
				(width 0.1524)
				(type default)
			)
			(layer "B.SilkS")
		)
		(fp_line
			(start 0.7874 -0.4064)
			(end -0.7874 -0.4064)
			(stroke
				(width 0.1524)
				(type default)
			)
			(layer "B.SilkS")
		)
		(fp_line
			(start -0.67945 0.3048)
			(end -0.120396 0.3048)
			(stroke
				(width 0.1)
				(type default)
			)
			(layer "B.Fab")
		)
		(fp_line
			(start -0.120396 0.3048)
			(end -0.120396 0.2794)
			(stroke
				(width 0.1)
				(type default)
			)
			(layer "B.Fab")
		)
		(fp_line
			(start 0.12065 0.3048)
			(end 0.67945 0.3048)
			(stroke
				(width 0.1)
				(type default)
			)
			(layer "B.Fab")
		)
		(fp_line
			(start 0.67945 0.3048)
			(end 0.67945 -0.305054)
			(stroke
				(width 0.1)
				(type default)
			)
			(layer "B.Fab")
		)
		(fp_line
			(start -0.120396 0.2794)
			(end 0.12065 0.2794)
			(stroke
				(width 0.1)
				(type default)
			)
			(layer "B.Fab")
		)
		(fp_line
			(start 0.12065 0.2794)
			(end 0.12065 0.3048)
			(stroke
				(width 0.1)
				(type default)
			)
			(layer "B.Fab")
		)
		(fp_line
			(start -0.12065 -0.2794)
			(end -0.12065 -0.3048)
			(stroke
				(width 0.1)
				(type default)
			)
			(layer "B.Fab")
		)
		(fp_line
			(start 0.12065 -0.2794)
			(end -0.12065 -0.2794)
			(stroke
				(width 0.1)
				(type default)
			)
			(layer "B.Fab")
		)
		(fp_line
			(start -0.67945 -0.3048)
			(end -0.67945 0.3048)
			(stroke
				(width 0.1)
				(type default)
			)
			(layer "B.Fab")
		)
		(fp_line
			(start -0.12065 -0.3048)
			(end -0.67945 -0.3048)
			(stroke
				(width 0.1)
				(type default)
			)
			(layer "B.Fab")
		)
		(fp_line
			(start 0.12065 -0.305054)
			(end 0.12065 -0.2794)
			(stroke
				(width 0.1)
				(type default)
			)
			(layer "B.Fab")
		)
		(fp_line
			(start 0.67945 -0.305054)
			(end 0.12065 -0.305054)
			(stroke
				(width 0.1)
				(type default)
			)
			(layer "B.Fab")
		)
		(pad "1" smd circle
			(at 0.40005 0 90)
			(size 0 0)
			(layers "B.Cu" "B.Mask" "B.Paste")
			(net "GND")
		)
		(pad "2" smd circle
			(at -0.40005 0 90)
			(size 0 0)
			(layers "B.Cu" "B.Mask" "B.Paste")
			(net "PWRGD_P52V_HS1_PG")
		)
	)
	(footprint ""
		(layer "B.Cu")
		(at 45.695616 -57.841642 180)
		(property "Reference" "R5902"
			(at 0 0 0)
			(layer "B.SilkS")
			(hide yes)
			(effects
				(font
					(size 1.27 1.27)
				)
				(justify mirror)
			)
		)
		(property "Value" ""
			(at 0 0 0)
			(layer "B.Fab")
			(effects
				(font
					(size 1.27 1.27)
				)
				(justify mirror)
			)
		)
		(duplicate_pad_numbers_are_jumpers no)
		(fp_line
			(start 0.7874 0.4064)
			(end 0.7874 -0.4064)
			(stroke
				(width 0.1524)
				(type default)
			)
			(layer "B.SilkS")
		)
		(fp_line
			(start 0.7874 -0.4064)
			(end -0.7874 -0.4064)
			(stroke
				(width 0.1524)
				(type default)
			)
			(layer "B.SilkS")
		)
		(fp_line
			(start -0.7874 0.4064)
			(end 0.7874 0.4064)
			(stroke
				(width 0.1524)
				(type default)
			)
			(layer "B.SilkS")
		)
		(fp_line
			(start -0.7874 -0.4064)
			(end -0.7874 0.4064)
			(stroke
				(width 0.1524)
				(type default)
			)
			(layer "B.SilkS")
		)
		(fp_line
			(start 0.67945 0.3048)
			(end 0.67945 -0.305054)
			(stroke
				(width 0.1)
				(type default)
			)
			(layer "B.Fab")
		)
		(fp_line
			(start 0.67945 -0.305054)
			(end 0.12065 -0.305054)
			(stroke
				(width 0.1)
				(type default)
			)
			(layer "B.Fab")
		)
		(fp_line
			(start 0.12065 0.3048)
			(end 0.67945 0.3048)
			(stroke
				(width 0.1)
				(type default)
			)
			(layer "B.Fab")
		)
		(fp_line
			(start 0.12065 0.2794)
			(end 0.12065 0.3048)
			(stroke
				(width 0.1)
				(type default)
			)
			(layer "B.Fab")
		)
		(fp_line
			(start 0.12065 -0.2794)
			(end -0.12065 -0.2794)
			(stroke
				(width 0.1)
				(type default)
			)
			(layer "B.Fab")
		)
		(fp_line
			(start 0.12065 -0.305054)
			(end 0.12065 -0.2794)
			(stroke
				(width 0.1)
				(type default)
			)
			(layer "B.Fab")
		)
		(fp_line
			(start -0.120396 0.3048)
			(end -0.120396 0.2794)
			(stroke
				(width 0.1)
				(type default)
			)
			(layer "B.Fab")
		)
		(fp_line
			(start -0.120396 0.2794)
			(end 0.12065 0.2794)
			(stroke
				(width 0.1)
				(type default)
			)
			(layer "B.Fab")
		)
		(fp_line
			(start -0.12065 -0.2794)
			(end -0.12065 -0.3048)
			(stroke
				(width 0.1)
				(type default)
			)
			(layer "B.Fab")
		)
		(fp_line
			(start -0.12065 -0.3048)
			(end -0.67945 -0.3048)
			(stroke
				(width 0.1)
				(type default)
			)
			(layer "B.Fab")
		)
		(fp_line
			(start -0.67945 0.3048)
			(end -0.120396 0.3048)
			(stroke
				(width 0.1)
				(type default)
			)
			(layer "B.Fab")
		)
		(fp_line
			(start -0.67945 -0.3048)
			(end -0.67945 0.3048)
			(stroke
				(width 0.1)
				(type default)
			)
			(layer "B.Fab")
		)
		(pad "1" smd circle
			(at 0.40005 0)
			(size 0 0)
			(layers "B.Cu" "B.Mask" "B.Paste")
			(net "P12V_HPDB_0_ISET")
		)
		(pad "2" smd circle
			(at -0.40005 0)
			(size 0 0)
			(layers "B.Cu" "B.Mask" "B.Paste")
			(net "P12V_HPDB_0_ISET_R")
		)
	)
)
